(kicad_pcb
	(version 20240108)
	(generator "pcbnew")
	(generator_version "8.0")
	(general
		(thickness 1.62)
		(legacy_teardrops no)
	)
	(paper "A4")
	(title_block
		(title "Jetson Orin Baseboard")
		(date "2025-03-12")
		(rev "1.3.4")
		(company "Antmicro Ltd")
		(comment 1 "www.antmicro.com")
		(comment 9 "footprints 137-139 of 677")
	)
	(layers
		(0 "F.Cu" signal)
		(1 "In1.Cu" signal)
		(2 "In2.Cu" signal)
		(3 "In3.Cu" signal)
		(4 "In4.Cu" jumper)
		(5 "In5.Cu" signal)
		(6 "In6.Cu" signal)
		(31 "B.Cu" signal)
		(32 "B.Adhes" user "B.Adhesive")
		(33 "F.Adhes" user "F.Adhesive")
		(34 "B.Paste" user)
		(35 "F.Paste" user)
		(36 "B.SilkS" user "B.Silkscreen")
		(37 "F.SilkS" user "F.Silkscreen")
		(38 "B.Mask" user)
		(39 "F.Mask" user)
		(40 "Dwgs.User" user "User.Drawings")
		(41 "Cmts.User" user "User.Comments")
		(42 "Eco1.User" user "User.Eco1")
		(43 "Eco2.User" user "User.Eco2")
		(44 "Edge.Cuts" user)
		(45 "Margin" user)
		(46 "B.CrtYd" user "B.Courtyard")
		(47 "F.CrtYd" user "F.Courtyard")
		(48 "B.Fab" user)
		(49 "F.Fab" user)
	)
	(footprint "antmicro-footprints:R_0402_1005Metric"
		(layer "F.Cu")
		(at 105.154938 106.045)
		(descr "Resistor SMD 0402")
		(tags "resistor SMD 0402")
		(property "Reference" "R203"
			(at -3.654938 0.405 0)
			(layer "F.SilkS")
			(effects
				(font
					(size 0.7 0.7)
					(thickness 0.15)
				)
				(justify left bottom)
			)
		)
		(property "Value" "R_0R_0402"
			(at 0 1.4 0)
			(layer "F.Fab")
			(effects
				(font
					(size 0.7 0.7)
					(thickness 0.15)
				)
				(justify left bottom)
			)
		)
		(property "Footprint" "antmicro-footprints:R_0402_1005Metric"
			(at 0 0 0)
			(layer "F.Fab")
			(hide yes)
			(effects
				(font
					(size 1.27 1.27)
					(thickness 0.15)
				)
			)
		)
		(property "Datasheet" "https://industrial.panasonic.com/cdbs/www-data/pdf/RDA0000/AOA0000C301.pdf"
			(at 0 0 0)
			(layer "F.Fab")
			(hide yes)
			(effects
				(font
					(size 1.27 1.27)
					(thickness 0.15)
				)
			)
		)
		(property "Author" "Antmicro"
			(at 0 0 0)
			(layer "F.Fab")
			(hide yes)
			(effects
				(font
					(size 1 1)
					(thickness 0.15)
				)
			)
		)
		(property "Current" "1A"
			(at 0 0 0)
			(layer "F.Fab")
			(hide yes)
			(effects
				(font
					(size 1 1)
					(thickness 0.15)
				)
			)
		)
		(property "License" "Apache-2.0"
			(at 0 0 0)
			(layer "F.Fab")
			(hide yes)
			(effects
				(font
					(size 1 1)
					(thickness 0.15)
				)
			)
		)
		(property "MPN" "ERJ2GE0R00X"
			(at 0 0 0)
			(layer "F.Fab")
			(hide yes)
			(effects
				(font
					(size 1 1)
					(thickness 0.15)
				)
			)
		)
		(property "Manufacturer" "Panasonic"
			(at 0 0 0)
			(layer "F.Fab")
			(hide yes)
			(effects
				(font
					(size 1 1)
					(thickness 0.15)
				)
			)
		)
		(property "Tolerance" ""
			(at 0 0 0)
			(layer "F.Fab")
			(hide yes)
			(effects
				(font
					(size 1 1)
					(thickness 0.15)
				)
			)
		)
		(property "Val" "0R"
			(at 0 0 0)
			(layer "F.Fab")
			(hide yes)
			(effects
				(font
					(size 1 1)
					(thickness 0.15)
				)
			)
		)
		(sheetname "USB3")
		(sheetfile "usb3.kicad_sch")
		(attr smd)
		(fp_rect
			(start -0.925 -0.47)
			(end 0.925 0.47)
			(stroke
				(width 0.05)
				(type default)
			)
			(fill none)
			(layer "F.CrtYd")
		)
		(fp_rect
			(start -0.5 -0.25)
			(end 0.5 0.25)
			(stroke
				(width 0.15)
				(type solid)
			)
			(fill none)
			(layer "F.Fab")
		)
		(fp_text user "${REFERENCE}"
			(at -0.95 3.168 0)
			(layer "F.Fab")
			(hide yes)
			(effects
				(font
					(size 0.7 0.7)
					(thickness 0.15)
				)
				(justify left bottom)
			)
		)
		(fp_text user "License: Apache-2.0"
			(at -0.95 5.169 0)
			(layer "F.Fab")
			(hide yes)
			(effects
				(font
					(size 0.7 0.7)
					(thickness 0.15)
				)
				(justify left bottom)
			)
		)
		(fp_text user "Author: Antmicro"
			(at -0.95 4.169 0)
			(layer "F.Fab")
			(hide yes)
			(effects
				(font
					(size 0.7 0.7)
					(thickness 0.15)
				)
				(justify left bottom)
			)
		)
		(pad "1" smd roundrect
			(at -0.48 0)
			(size 0.59 0.64)
			(layers "F.Cu" "F.Paste" "F.Mask")
			(roundrect_rratio 0.25)
			(net 167 "USBSS2_TX_N")
			(pintype "passive")
		)
		(pad "2" smd roundrect
			(at 0.48 0)
			(size 0.59 0.64)
			(layers "F.Cu" "F.Paste" "F.Mask")
			(roundrect_rratio 0.25)
			(net 612 "/USB3/USBSS1_C_TX_P")
			(pintype "passive")
		)
	)
	(footprint "antmicro-footprints:WQFN-30-1EP_4.6x2.6mm_P0.4mm"
		(layer "F.Cu")
		(at 108.889938 106.545)
		(property "Reference" "U17"
			(at 2.690062 -0.415 90)
			(layer "F.SilkS")
			(effects
				(font
					(size 0.7 0.7)
					(thickness 0.15)
				)
				(justify left bottom)
			)
		)
		(property "Value" "HD3SS3220RNH"
			(at 0 3.5 180)
			(layer "F.Fab")
			(effects
				(font
					(size 0.7 0.7)
					(thickness 0.15)
				)
				(justify left bottom)
			)
		)
		(property "Footprint" "antmicro-footprints:WQFN-30-1EP_4.6x2.6mm_P0.4mm"
			(at 0 0 0)
			(layer "F.Fab")
			(hide yes)
			(effects
				(font
					(size 1.27 1.27)
					(thickness 0.15)
				)
			)
		)
		(property "Datasheet" "https://www.ti.com/lit/ds/symlink/hd3ss3220.pdf?ts=1663000043694&ref_url=https%253A%252F%252Fwww.google.com%252F"
			(at 0 0 0)
			(layer "F.Fab")
			(hide yes)
			(effects
				(font
					(size 1.27 1.27)
					(thickness 0.15)
				)
			)
		)
		(property "Author" "Antmicro"
			(at 0 0 0)
			(layer "F.Fab")
			(hide yes)
			(effects
				(font
					(size 1 1)
					(thickness 0.15)
				)
			)
		)
		(property "License" "Apache-2.0"
			(at 0 0 0)
			(layer "F.Fab")
			(hide yes)
			(effects
				(font
					(size 1 1)
					(thickness 0.15)
				)
			)
		)
		(property "MPN" "HD3SS3220RNHT"
			(at 0 0 0)
			(layer "F.Fab")
			(hide yes)
			(effects
				(font
					(size 1 1)
					(thickness 0.15)
				)
			)
		)
		(property "Manufacturer" "Texas Instruments"
			(at 0 0 0)
			(layer "F.Fab")
			(hide yes)
			(effects
				(font
					(size 1 1)
					(thickness 0.15)
				)
			)
		)
		(sheetname "USB3")
		(sheetfile "usb3.kicad_sch")
		(attr smd)
		(fp_line
			(start -1.253 -2.26)
			(end -1.253 -2.01)
			(stroke
				(width 0.15)
				(type solid)
			)
			(layer "F.SilkS")
		)
		(fp_line
			(start -1.253 -2.26)
			(end -1.003 -2.26)
			(stroke
				(width 0.15)
				(type solid)
			)
			(layer "F.SilkS")
		)
		(fp_line
			(start -1.253 2.24)
			(end -1.253 1.99)
			(stroke
				(width 0.15)
				(type solid)
			)
			(layer "F.SilkS")
		)
		(fp_line
			(start -1.253 2.24)
			(end -1.003 2.24)
			(stroke
				(width 0.15)
				(type solid)
			)
			(layer "F.SilkS")
		)
		(fp_line
			(start 1.247 -2.26)
			(end 0.997 -2.26)
			(stroke
				(width 0.15)
				(type solid)
			)
			(layer "F.SilkS")
		)
		(fp_line
			(start 1.247 -2.26)
			(end 1.247 -2.01)
			(stroke
				(width 0.15)
				(type solid)
			)
			(layer "F.SilkS")
		)
		(fp_line
			(start 1.247 2.24)
			(end 0.997 2.24)
			(stroke
				(width 0.15)
				(type solid)
			)
			(layer "F.SilkS")
		)
		(fp_line
			(start 1.247 2.24)
			(end 1.247 1.99)
			(stroke
				(width 0.15)
				(type solid)
			)
			(layer "F.SilkS")
		)
		(fp_circle
			(center -1.5 -2.5)
			(end -1.45 -2.5)
			(stroke
				(width 0.15)
				(type solid)
			)
			(fill solid)
			(layer "F.SilkS")
		)
		(fp_rect
			(start -1.6 -2.6)
			(end 1.6 2.6)
			(stroke
				(width 0.05)
				(type solid)
			)
			(fill none)
			(layer "F.CrtYd")
		)
		(fp_rect
			(start -1.3 -2.3)
			(end 1.3 2.3)
			(stroke
				(width 0.15)
				(type solid)
			)
			(fill none)
			(layer "F.Fab")
		)
		(fp_text user "License: Apache-2.0"
			(at -1.6 7.199 0)
			(layer "F.Fab")
			(hide yes)
			(effects
				(font
					(size 0.7 0.7)
					(thickness 0.15)
				)
				(justify left bottom)
			)
		)
		(fp_text user "Author: Antmicro"
			(at -1.6 6 0)
			(layer "F.Fab")
			(hide yes)
			(effects
				(font
					(size 0.7 0.7)
					(thickness 0.15)
				)
				(justify left bottom)
			)
		)
		(fp_text user "${REFERENCE}"
			(at -1.6 4.8 0)
			(layer "F.Fab")
			(hide yes)
			(effects
				(font
					(size 0.7 0.7)
					(thickness 0.15)
				)
				(justify left bottom)
			)
		)
		(pad "1" smd rect
			(at -1.232 -1.809 90)
			(size 0.2 0.45)
			(layers "F.Cu" "F.Paste" "F.Mask")
			(net 283 "/USB3/USBC1_CC2")
			(pinfunction "CC2")
			(pintype "passive")
		)
		(pad "2" smd rect
			(at -1.203 -1.41 90)
			(size 0.2 0.5)
			(layers "F.Cu" "F.Paste" "F.Mask")
			(net 282 "/USB3/USBC1_CC1")
			(pinfunction "CC1")
			(pintype "passive")
		)
		(pad "3" smd rect
			(at -1.203 -1.01 90)
			(size 0.2 0.5)
			(layers "F.Cu" "F.Paste" "F.Mask")
			(net 316 "/USB3/USBC1_I_MODE")
			(pinfunction "CURRENT_MODE")
			(pintype "passive")
		)
		(pad "4" smd rect
			(at -1.203 -0.609 90)
			(size 0.2 0.5)
			(layers "F.Cu" "F.Paste" "F.Mask")
			(net 315 "/USB3/USBC1_PORT")
			(pinfunction "PORT")
			(pintype "passive")
		)
		(pad "5" smd rect
			(at -1.203 -0.21 90)
			(size 0.2 0.5)
			(layers "F.Cu" "F.Paste" "F.Mask")
			(net 365 "/USB3/USBC1_VBUS_DET")
			(pinfunction "VBUS_DET")
			(pintype "passive")
		)
		(pad "6" smd rect
			(at -1.203 0.191 90)
			(size 0.2 0.5)
			(layers "F.Cu" "F.Paste" "F.Mask")
			(net 612 "/USB3/USBSS1_C_TX_P")
			(pinfunction "TX+")
			(pintype "passive")
		)
		(pad "7" smd rect
			(at -1.203 0.59 90)
			(size 0.2 0.5)
			(layers "F.Cu" "F.Paste" "F.Mask")
			(net 610 "/USB3/USBSS1_C_TX_N")
			(pinfunction "TX-")
			(pintype "passive")
		)
		(pad "8" smd rect
			(at -1.203 0.99 90)
			(size 0.2 0.5)
			(layers "F.Cu" "F.Paste" "F.Mask")
			(net 87 "+3V3")
			(pinfunction "VCC33")
			(pintype "passive")
		)
		(pad "9" smd rect
			(at -1.203 1.391 90)
			(size 0.2 0.5)
			(layers "F.Cu" "F.Paste" "F.Mask")
			(net 611 "/USB3/USBSS1_C_RX_P")
			(pinfunction "RX+")
			(pintype "passive")
		)
		(pad "10" smd rect
			(at -1.232 1.79 90)
			(size 0.2 0.45)
			(layers "F.Cu" "F.Paste" "F.Mask")
			(net 609 "/USB3/USBSS1_C_RX_N")
			(pinfunction "RX-")
			(pintype "passive")
		)
		(pad "11" smd rect
			(at -0.804 2.191)
			(size 0.2 0.45)
			(layers "F.Cu" "F.Paste" "F.Mask")
			(net 364 "/USB3/USBC1_DIR")
			(pinfunction "DIR")
			(pintype "passive")
		)
		(pad "12" smd rect
			(at -0.403 2.191)
			(size 0.2 0.5)
			(layers "F.Cu" "F.Paste" "F.Mask")
			(net 318 "/USB3/~{USBC1_EN_MUX}")
			(pinfunction "ENn_MUX")
			(pintype "passive")
		)
		(pad "13" smd rect
			(at -0.003 2.191)
			(size 0.2 0.5)
			(layers "F.Cu" "F.Paste" "F.Mask")
			(net 1 "GND")
			(pinfunction "GND")
			(pintype "passive")
		)
		(pad "14" smd rect
			(at 0.396 2.191)
			(size 0.2 0.5)
			(layers "F.Cu" "F.Paste" "F.Mask")
			(net 366 "/USB3/USBC1_RX1_N")
			(pinfunction "RX1-")
			(pintype "passive")
		)
		(pad "15" smd rect
			(at 0.797 2.191)
			(size 0.2 0.45)
			(layers "F.Cu" "F.Paste" "F.Mask")
			(net 368 "/USB3/USBC1_RX1_P")
			(pinfunction "RX1+")
			(pintype "passive")
		)
		(pad "16" smd rect
			(at 1.222 1.79 90)
			(size 0.2 0.45)
			(layers "F.Cu" "F.Paste" "F.Mask")
			(net 264 "/USB3/USBC1_TX1_N")
			(pinfunction "TX1-")
			(pintype "passive")
		)
		(pad "17" smd rect
			(at 1.196 1.391 90)
			(size 0.2 0.5)
			(layers "F.Cu" "F.Paste" "F.Mask")
			(net 266 "/USB3/USBC1_TX1_P")
			(pinfunction "TX1+")
			(pintype "passive")
		)
		(pad "18" smd rect
			(at 1.196 0.99 90)
			(size 0.2 0.5)
			(layers "F.Cu" "F.Paste" "F.Mask")
			(net 369 "/USB3/USBC1_RX2_N")
			(pinfunction "RX2-")
			(pintype "passive")
		)
		(pad "19" smd rect
			(at 1.196 0.59 90)
			(size 0.2 0.5)
			(layers "F.Cu" "F.Paste" "F.Mask")
			(net 390 "/USB3/USBC1_RX2_P")
			(pinfunction "RX2+")
			(pintype "passive")
		)
		(pad "20" smd rect
			(at 1.196 0.191 90)
			(size 0.2 0.5)
			(layers "F.Cu" "F.Paste" "F.Mask")
			(net 262 "/USB3/USBC1_TX2_N")
			(pinfunction "TX2-")
			(pintype "passive")
		)
		(pad "21" smd rect
			(at 1.196 -0.21 90)
			(size 0.2 0.5)
			(layers "F.Cu" "F.Paste" "F.Mask")
			(net 268 "/USB3/USBC1_TX2_P")
			(pinfunction "TX2+")
			(pintype "passive")
		)
		(pad "22" smd rect
			(at 1.196 -0.609 90)
			(size 0.2 0.5)
			(layers "F.Cu" "F.Paste" "F.Mask")
			(net 314 "/USB3/USBC1_ADDR")
			(pinfunction "ADDR")
			(pintype "passive")
		)
		(pad "23" smd rect
			(at 1.196 -1.01 90)
			(size 0.2 0.5)
			(layers "F.Cu" "F.Paste" "F.Mask")
			(net 317 "/USB3/~{USBC1_INT}")
			(pinfunction "INT_N/OUT3")
			(pintype "passive")
		)
		(pad "24" smd rect
			(at 1.196 -1.41 90)
			(size 0.2 0.5)
			(layers "F.Cu" "F.Paste" "F.Mask")
			(net 391 "/USB3/USBC1_FAULT_N")
			(pinfunction "VCONN_FAULT_N")
			(pintype "passive")
		)
		(pad "25" smd rect
			(at 1.222 -1.809 90)
			(size 0.2 0.45)
			(layers "F.Cu" "F.Paste" "F.Mask")
			(net 362 "/USB3/USBC1_I2C_SDA")
			(pinfunction "SDA/OUT1")
			(pintype "passive")
		)
		(pad "26" smd rect
			(at 0.797 -2.21)
			(size 0.2 0.45)
			(layers "F.Cu" "F.Paste" "F.Mask")
			(net 363 "/USB3/USBC1_ISC_SCL")
			(pinfunction "SCL/OUT2")
			(pintype "passive")
		)
		(pad "27" smd rect
			(at 0.396 -2.21)
			(size 0.2 0.5)
			(layers "F.Cu" "F.Paste" "F.Mask")
			(net 284 "/USB3/USBC1_ID")
			(pinfunction "ID")
			(pintype "passive")
		)
		(pad "28" smd rect
			(at -0.003 -2.21)
			(size 0.2 0.5)
			(layers "F.Cu" "F.Paste" "F.Mask")
			(net 1 "GND")
			(pinfunction "GND")
			(pintype "passive")
		)
		(pad "29" smd rect
			(at -0.403 -2.21)
			(size 0.2 0.5)
			(layers "F.Cu" "F.Paste" "F.Mask")
			(net 319 "/USB3/~{USBC1_EN_CC}")
			(pinfunction "ENn_CC")
			(pintype "passive")
		)
		(pad "30" smd rect
			(at -0.804 -2.21)
			(size 0.2 0.45)
			(layers "F.Cu" "F.Paste" "F.Mask")
			(net 99 "+5V")
			(pinfunction "VDD5")
			(pintype "passive")
		)
		(pad "31" smd rect
			(at -0.003 -0.01)
			(size 1.2 3.2)
			(layers "F.Cu" "F.Paste" "F.Mask")
			(net 1 "GND")
			(pinfunction "GND")
			(pintype "passive")
		)
	)
	(footprint "antmicro-footprints:C_0402_1005Metric"
		(layer "F.Cu")
		(at 80.23 89.13 -90)
		(descr "Capacitor SMD 0402")
		(tags "capacitor SMD 0402")
		(property "Reference" "C123"
			(at -1.73 -2.43 90)
			(layer "F.SilkS")
			(effects
				(font
					(size 0.7 0.7)
					(thickness 0.15)
				)
				(justify right bottom)
			)
		)
		(property "Value" "C_1u_0402"
			(at -1.022927 2.155213 90)
			(layer "F.Fab")
			(effects
				(font
					(size 0.7 0.7)
					(thickness 0.15)
				)
				(justify right bottom)
			)
		)
		(property "Footprint" "antmicro-footprints:C_0402_1005Metric"
			(at 0 0 -90)
			(layer "F.Fab")
			(hide yes)
			(effects
				(font
					(size 1.27 1.27)
					(thickness 0.15)
				)
			)
		)
		(property "Datasheet" "https://product.tdk.com/en/search/capacitor/ceramic/mlcc/info?part_no=C1005X6S1A105K050BC"
			(at 0 0 -90)
			(layer "F.Fab")
			(hide yes)
			(effects
				(font
					(size 1.27 1.27)
					(thickness 0.15)
				)
			)
		)
		(property "Author" "Antmicro"
			(at -8.9 169.36 0)
			(layer "F.Fab")
			(hide yes)
			(effects
				(font
					(size 1 1)
					(thickness 0.15)
				)
			)
		)
		(property "Dielectric" ""
			(at -8.9 169.36 0)
			(layer "F.Fab")
			(hide yes)
			(effects
				(font
					(size 1 1)
					(thickness 0.15)
				)
			)
		)
		(property "License" "Apache-2.0"
			(at -8.9 169.36 0)
			(layer "F.Fab")
			(hide yes)
			(effects
				(font
					(size 1 1)
					(thickness 0.15)
				)
			)
		)
		(property "MPN" "C1005X6S1A105K050BC"
			(at -8.9 169.36 0)
			(layer "F.Fab")
			(hide yes)
			(effects
				(font
					(size 1 1)
					(thickness 0.15)
				)
			)
		)
		(property "Manufacturer" "TDK"
			(at -8.9 169.36 0)
			(layer "F.Fab")
			(hide yes)
			(effects
				(font
					(size 1 1)
					(thickness 0.15)
				)
			)
		)
		(property "Val" "1u"
			(at -8.9 169.36 0)
			(layer "F.Fab")
			(hide yes)
			(effects
				(font
					(size 1 1)
					(thickness 0.15)
				)
			)
		)
		(property "Voltage" ""
			(at -8.9 169.36 0)
			(layer "F.Fab")
			(hide yes)
			(effects
				(font
					(size 1 1)
					(thickness 0.15)
				)
			)
		)
		(sheetname "Supply")
		(sheetfile "supply.kicad_sch")
		(attr smd)
		(fp_rect
			(start -0.925 -0.47)
			(end 0.925 0.47)
			(stroke
				(width 0.05)
				(type default)
			)
			(fill none)
			(layer "F.CrtYd")
		)
		(fp_line
			(start -0.494 0.248)
			(end -0.494 -0.25)
			(stroke
				(width 0.15)
				(type solid)
			)
			(layer "F.Fab")
		)
		(fp_line
			(start 0.504 0.248)
			(end -0.494 0.248)
			(stroke
				(width 0.15)
				(type solid)
			)
			(layer "F.Fab")
		)
		(fp_line
			(start -0.494 -0.25)
			(end 0.504 -0.25)
			(stroke
				(width 0.15)
				(type solid)
			)
			(layer "F.Fab")
		)
		(fp_line
			(start 0.504 -0.25)
			(end 0.504 0.248)
			(stroke
				(width 0.15)
				(type solid)
			)
			(layer "F.Fab")
		)
		(fp_text user "License: Apache-2.0"
			(at -0.939 5.799 90)
			(layer "F.Fab")
			(hide yes)
			(effects
				(font
					(size 0.7 0.7)
					(thickness 0.15)
				)
				(justify right bottom)
			)
		)
		(fp_text user "${REFERENCE}"
			(at -0.939 4.599 90)
			(layer "F.Fab")
			(hide yes)
			(effects
				(font
					(size 0.7 0.7)
					(thickness 0.15)
				)
				(justify right bottom)
			)
		)
		(fp_text user "Author: Antmicro"
			(at -0.939 3.399 90)
			(layer "F.Fab")
			(hide yes)
			(effects
				(font
					(size 0.7 0.7)
					(thickness 0.15)
				)
				(justify right bottom)
			)
		)
		(pad "1" smd roundrect
			(at -0.48 0 270)
			(size 0.59 0.64)
			(layers "F.Cu" "F.Paste" "F.Mask")
			(roundrect_rratio 0.25)
			(net 1 "GND")
			(pintype "passive")
		)
		(pad "2" smd roundrect
			(at 0.48 0 270)
			(size 0.59 0.64)
			(layers "F.Cu" "F.Paste" "F.Mask")
			(roundrect_rratio 0.25)
			(net 177 "/Supply/3V3_VDD")
			(pintype "passive")
		)
	)
)
